# BASEBOARD_FAB2 (Tioga Pass) — schematic netlist excerpt (pin names and nets, part order shuffled) for the footprints in the layout excerpt that follows; sources: Cadence DE-HDL packaged netlist, KiCad conversion of Wiwynn_Tioga_Pass_MB.brd

EU7G1  PXM1310B  IC  pkg QFN  page 215
  BPWM1  = NC
  DNC(0)  = NC
  APWM3  = NC
  APWM2  = VR_PVDDQ_ABC_PWM2
  APWM1  = VR_PVDDQ_ABC_PWM1
  SDA  = SMB_VR_STBY_LVC3_SDA
  SCL  = SMB_VR_STBY_LVC3_SCL
  RESET_N  = NC
  AVRRDY  = PWRGD_PVDDQ_ABC_R
  AVREN  = VR_PVDDQ_ABC_VREN
  VRHOT_N  = IRQ_PVDDQ_ABC_VRHOT_LVT3_R_N
  PINALRT_N  = NC
  MP0  = PU_VR_PVDDQ_ABC_FAULT1
  MP1  = TP_PVDDQ_ABC_MP1
  VCLK  = SVID_CLK_PVDDQ_ABC
  VDIO  = SVID_VDIO_PVDDQ_ABC
  VALRT_N  = SVID_ALERT_PVDDQ_ABC
  MP2  = TP_PVDDQ_ABC_MP2
  AVSEN  = VR_PVDDQ_ABC_AVSP
  AVREF  = VSENSE_PVDDQ_ABC_N
  AIREF1  = VR_PVDDQ_ABC_AIREF1
  AISEN1  = ISENSE_PVDDQ_ABC_PH1_IMON
  AIREF2  = VR_PVDDQ_ABC_AIREF2
  AISEN2  = ISENSE_PVDDQ_ABC_PH2_IMON
  AIREF3  = NC
  AISEN3  = NC
  GND  = GND
  DNC(1)  = NC
  BVSEN  = NC
  BVREF  = NC
  BIREF1  = NC
  BISEN1  = GND
  XADDR2  = VR_PVDDQ_ABC_XADDR2
  BTSEN  = NC
  ATSEN  = A_TSENSE_PVDDQ_ABC
  XADDR1  = VR_PVDDQ_ABC_XADDR1
  VINSEN  = VR_PVDDQ_ABC_VINSEN
  IINSEN  = VR_PVDDQ_ABC_AIINSEN
  VDD  = VR_PVDDQ_ABC_VDD
  VD12  = VR_PVDDQ_ABC_VD12
  THPAD  = GND

(kicad_pcb
	(version 20260206)
	(generator "pcbnew")
	(generator_version "10.0")
	(general
		(thickness 1.6)
		(legacy_teardrops no)
	)
	(paper "A4")
	(title_block
		(title "Wiwynn_Tioga_Pass_MB.brd")
		(comment 1 "Tioga Pass / footprint 467 of 4770 (EU7G1), pads 1-17 of 41")
	)
	(layers
		(0 "F.Cu" signal "TOP")
		(4 "In1.Cu" signal "L2GND")
		(6 "In2.Cu" signal "L3")
		(8 "In3.Cu" signal "L4GND")
		(10 "In4.Cu" signal "L5")
		(12 "In5.Cu" signal "L6GND")
		(14 "In6.Cu" signal "L7VCC")
		(16 "In7.Cu" signal "L8VCC")
		(18 "In8.Cu" signal "L9GND")
		(20 "In9.Cu" signal "L10")
		(22 "In10.Cu" signal "L11GND")
		(24 "In11.Cu" signal "L12")
		(26 "In12.Cu" signal "L13GND")
		(2 "B.Cu" signal "BOTTOM")
		(9 "F.Adhes" user "F.Adhesive")
		(11 "B.Adhes" user "B.Adhesive")
		(13 "F.Paste" user "Package Geometry/Pastemask Top")
		(15 "B.Paste" user "Package Geometry/Pastemask Bottom")
		(5 "F.SilkS" user "Ref Des/Silkscreen Top")
		(7 "B.SilkS" user "Ref Des/Silkscreen Bottom")
		(1 "F.Mask" user "Board Geometry/Soldermask Top")
		(3 "B.Mask" user "Board Geometry/Soldermask Bottom")
		(17 "Dwgs.User" user "User.Drawings")
		(19 "Cmts.User" user "User.Comments")
		(21 "Eco1.User" user "User.Eco1")
		(23 "Eco2.User" user "User.Eco2")
		(25 "Edge.Cuts" user "Board Geometry/Outline")
		(27 "Margin" user)
		(31 "F.CrtYd" user "Package Geometry/Place Bound Top")
		(29 "B.CrtYd" user "Package Geometry/Place Bound Bottom")
		(35 "F.Fab" user "Ref Des/Assembly Top")
		(33 "B.Fab" user "Ref Des/Assembly Bottom")
	)
	(footprint ""
		(layer "F.Cu")
		(at 344.678 -15.367 -90)
		(property "Reference" "EU7G1"
			(at 1.27 4.03733 90)
			(unlocked yes)
			(layer "F.SilkS")
			(effects
				(font
					(size 0.7874 0.5842)
					(thickness 0.1524)
				)
				(justify left)
			)
		)
		(property "Value" ""
			(at 0 0 270)
			(layer "F.Fab")
			(effects
				(font
					(size 1.27 1.27)
				)
			)
		)
		(duplicate_pad_numbers_are_jumpers no)
		(pad "1" smd custom
			(at -2.4511 -1.800098 270)
			(size 0.0508 0.0508)
			(layers "F.Cu" "F.Mask" "F.Paste")
			(net "Net_281")
			(options
				(clearance outline)
				(anchor circle)
			)
			(primitives
				(gr_poly
					(pts
						(arc
							(start 0.254 -0.1016)
							(mid 0.3556 0)
							(end 0.254 0.1016)
						)
						(xy -0.3556 0.1016) (xy -0.3556 -0.1016)
					)
					(width 0)
					(fill yes)
				)
			)
		)
		(pad "2" smd custom
			(at -2.4511 -1.400048 270)
			(size 0.0508 0.0508)
			(layers "F.Cu" "F.Mask" "F.Paste")
			(net "Net_345")
			(options
				(clearance outline)
				(anchor circle)
			)
			(primitives
				(gr_poly
					(pts
						(arc
							(start 0.254 -0.1016)
							(mid 0.3556 0)
							(end 0.254 0.1016)
						)
						(xy -0.3556 0.1016) (xy -0.3556 -0.1016)
					)
					(width 0)
					(fill yes)
				)
			)
		)
		(pad "3" smd custom
			(at -2.4511 -0.999998 270)
			(size 0.0508 0.0508)
			(layers "F.Cu" "F.Mask" "F.Paste")
			(net "Net_242")
			(options
				(clearance outline)
				(anchor circle)
			)
			(primitives
				(gr_poly
					(pts
						(arc
							(start 0.254 -0.1016)
							(mid 0.3556 0)
							(end 0.254 0.1016)
						)
						(xy -0.3556 0.1016) (xy -0.3556 -0.1016)
					)
					(width 0)
					(fill yes)
				)
			)
		)
		(pad "4" smd custom
			(at -2.4511 -0.599948 270)
			(size 0.0508 0.0508)
			(layers "F.Cu" "F.Mask" "F.Paste")
			(net "VR_PVDDQ_ABC_PWM2")
			(options
				(clearance outline)
				(anchor circle)
			)
			(primitives
				(gr_poly
					(pts
						(arc
							(start 0.254 -0.1016)
							(mid 0.3556 0)
							(end 0.254 0.1016)
						)
						(xy -0.3556 0.1016) (xy -0.3556 -0.1016)
					)
					(width 0)
					(fill yes)
				)
			)
		)
		(pad "5" smd custom
			(at -2.4511 -0.199898 270)
			(size 0.0508 0.0508)
			(layers "F.Cu" "F.Mask" "F.Paste")
			(net "VR_PVDDQ_ABC_PWM1")
			(options
				(clearance outline)
				(anchor circle)
			)
			(primitives
				(gr_poly
					(pts
						(arc
							(start 0.254 -0.1016)
							(mid 0.3556 0)
							(end 0.254 0.1016)
						)
						(xy -0.3556 0.1016) (xy -0.3556 -0.1016)
					)
					(width 0)
					(fill yes)
				)
			)
		)
		(pad "6" smd custom
			(at -2.4511 0.199898 270)
			(size 0.0508 0.0508)
			(layers "F.Cu" "F.Mask" "F.Paste")
			(net "SMB_VR_STBY_LVC3_SDA")
			(options
				(clearance outline)
				(anchor circle)
			)
			(primitives
				(gr_poly
					(pts
						(arc
							(start 0.254 -0.1016)
							(mid 0.3556 0)
							(end 0.254 0.1016)
						)
						(xy -0.3556 0.1016) (xy -0.3556 -0.1016)
					)
					(width 0)
					(fill yes)
				)
			)
		)
		(pad "7" smd custom
			(at -2.4511 0.599948 270)
			(size 0.0508 0.0508)
			(layers "F.Cu" "F.Mask" "F.Paste")
			(net "SMB_VR_STBY_LVC3_SCL")
			(options
				(clearance outline)
				(anchor circle)
			)
			(primitives
				(gr_poly
					(pts
						(arc
							(start 0.254 -0.1016)
							(mid 0.3556 0)
							(end 0.254 0.1016)
						)
						(xy -0.3556 0.1016) (xy -0.3556 -0.1016)
					)
					(width 0)
					(fill yes)
				)
			)
		)
		(pad "8" smd custom
			(at -2.4511 0.999998 270)
			(size 0.0508 0.0508)
			(layers "F.Cu" "F.Mask" "F.Paste")
			(net "Net_282")
			(options
				(clearance outline)
				(anchor circle)
			)
			(primitives
				(gr_poly
					(pts
						(arc
							(start 0.254 -0.1016)
							(mid 0.3556 0)
							(end 0.254 0.1016)
						)
						(xy -0.3556 0.1016) (xy -0.3556 -0.1016)
					)
					(width 0)
					(fill yes)
				)
			)
		)
		(pad "9" smd custom
			(at -2.4511 1.400048 270)
			(size 0.0508 0.0508)
			(layers "F.Cu" "F.Mask" "F.Paste")
			(net "PWRGD_PVDDQ_ABC_R")
			(options
				(clearance outline)
				(anchor circle)
			)
			(primitives
				(gr_poly
					(pts
						(arc
							(start 0.254 -0.1016)
							(mid 0.3556 0)
							(end 0.254 0.1016)
						)
						(xy -0.3556 0.1016) (xy -0.3556 -0.1016)
					)
					(width 0)
					(fill yes)
				)
			)
		)
		(pad "10" smd custom
			(at -2.4511 1.800098 270)
			(size 0.0508 0.0508)
			(layers "F.Cu" "F.Mask" "F.Paste")
			(net "VR_PVDDQ_ABC_VREN")
			(options
				(clearance outline)
				(anchor circle)
			)
			(primitives
				(gr_poly
					(pts
						(arc
							(start 0.254 -0.1016)
							(mid 0.3556 0)
							(end 0.254 0.1016)
						)
						(xy -0.3556 0.1016) (xy -0.3556 -0.1016)
					)
					(width 0)
					(fill yes)
				)
			)
		)
		(pad "11" smd custom
			(at -1.800098 2.4511 270)
			(size 0.0508 0.0508)
			(layers "F.Cu" "F.Mask" "F.Paste")
			(net "IRQ_PVDDQ_ABC_VRHOT_LVT3_R_N")
			(options
				(clearance outline)
				(anchor circle)
			)
			(primitives
				(gr_poly
					(pts
						(arc
							(start -0.1016 -0.254)
							(mid 0 -0.3556)
							(end 0.1016 -0.254)
						)
						(xy 0.1016 0.3556) (xy -0.1016 0.3556)
					)
					(width 0)
					(fill yes)
				)
			)
		)
		(pad "12" smd custom
			(at -1.400048 2.4511 270)
			(size 0.0508 0.0508)
			(layers "F.Cu" "F.Mask" "F.Paste")
			(net "Net_221")
			(options
				(clearance outline)
				(anchor circle)
			)
			(primitives
				(gr_poly
					(pts
						(arc
							(start -0.1016 -0.254)
							(mid 0 -0.3556)
							(end 0.1016 -0.254)
						)
						(xy 0.1016 0.3556) (xy -0.1016 0.3556)
					)
					(width 0)
					(fill yes)
				)
			)
		)
		(pad "13" smd custom
			(at -0.999998 2.4511 270)
			(size 0.0508 0.0508)
			(layers "F.Cu" "F.Mask" "F.Paste")
			(net "PU_VR_PVDDQ_ABC_FAULT1")
			(options
				(clearance outline)
				(anchor circle)
			)
			(primitives
				(gr_poly
					(pts
						(arc
							(start -0.1016 -0.254)
							(mid 0 -0.3556)
							(end 0.1016 -0.254)
						)
						(xy 0.1016 0.3556) (xy -0.1016 0.3556)
					)
					(width 0)
					(fill yes)
				)
			)
		)
		(pad "14" smd custom
			(at -0.599948 2.4511 270)
			(size 0.0508 0.0508)
			(layers "F.Cu" "F.Mask" "F.Paste")
			(net "TP_PVDDQ_ABC_MP1")
			(options
				(clearance outline)
				(anchor circle)
			)
			(primitives
				(gr_poly
					(pts
						(arc
							(start -0.1016 -0.254)
							(mid 0 -0.3556)
							(end 0.1016 -0.254)
						)
						(xy 0.1016 0.3556) (xy -0.1016 0.3556)
					)
					(width 0)
					(fill yes)
				)
			)
		)
		(pad "15" smd custom
			(at -0.199898 2.4511 270)
			(size 0.0508 0.0508)
			(layers "F.Cu" "F.Mask" "F.Paste")
			(net "SVID_CLK_PVDDQ_ABC")
			(options
				(clearance outline)
				(anchor circle)
			)
			(primitives
				(gr_poly
					(pts
						(arc
							(start -0.1016 -0.254)
							(mid 0 -0.3556)
							(end 0.1016 -0.254)
						)
						(xy 0.1016 0.3556) (xy -0.1016 0.3556)
					)
					(width 0)
					(fill yes)
				)
			)
		)
		(pad "16" smd custom
			(at 0.199898 2.4511 270)
			(size 0.0508 0.0508)
			(layers "F.Cu" "F.Mask" "F.Paste")
			(net "SVID_VDIO_PVDDQ_ABC")
			(options
				(clearance outline)
				(anchor circle)
			)
			(primitives
				(gr_poly
					(pts
						(arc
							(start -0.1016 -0.254)
							(mid 0 -0.3556)
							(end 0.1016 -0.254)
						)
						(xy 0.1016 0.3556) (xy -0.1016 0.3556)
					)
					(width 0)
					(fill yes)
				)
			)
		)
		(pad "17" smd custom
			(at 0.599948 2.4511 270)
			(size 0.0508 0.0508)
			(layers "F.Cu" "F.Mask" "F.Paste")
			(net "SVID_ALERT_PVDDQ_ABC")
			(options
				(clearance outline)
				(anchor circle)
			)
			(primitives
				(gr_poly
					(pts
						(arc
							(start -0.1016 -0.254)
							(mid 0 -0.3556)
							(end 0.1016 -0.254)
						)
						(xy 0.1016 0.3556) (xy -0.1016 0.3556)
					)
					(width 0)
					(fill yes)
				)
			)
		)
	)
)
